# BASEBOARD_FAB2 (Tioga Pass) — schematic netlist excerpt (pin names and nets, part order shuffled) for the footprints in the layout excerpt that follows; sources: Cadence DE-HDL packaged netlist, KiCad conversion of Wiwynn_Tioga_Pass_MB.brd

J30W1  SKT-USB32-8-GP  pkg SOCKET-G4  page 253
  GND(0)  = GND
  SSTXP1  = USB3_P01_FB_TXP
  SSTXN1  = USB3_P01_FB_TXN
  VBUS(0)  = P5V_STBY_USBC
  CC1  = NC
  DP1  = NC
  DN1  = NC
  SBU1  = NC
  VBUS(1)  = P5V_STBY_USBC
  SSRXN2  = NC
  SSRXP2  = NC
  GND(1)  = GND
  GND(2)  = GND
  SSTXP2  = NC
  SSTXN2  = NC
  VBUS(2)  = P5V_STBY_USBC
  CC2  = NC
  DP2  = NC
  DN2  = NC
  SBU2  = NC
  VBUS(3)  = P5V_STBY_USBC
  SSRXN1  = USB3_P01_FB_RXN
  SSRXP1  = USB3_P01_FB_RXP
  GND(3)  = GND
  NP1  = NC
  NP2  = NC
  PTH1  = GND
  PTH2  = GND
  PTH3  = GND
  PTH4  = GND
  PTH5  = GND
  PTH6  = GND
  PTH7  = GND
  PTH8  = GND

(kicad_pcb
	(version 20260206)
	(generator "pcbnew")
	(generator_version "10.0")
	(general
		(thickness 1.6)
		(legacy_teardrops no)
	)
	(paper "A4")
	(title_block
		(title "Wiwynn_Tioga_Pass_MB.brd")
		(comment 1 "Tioga Pass / footprint 189 of 4770 (J30W1), pads 34-34 of 34")
	)
	(layers
		(0 "F.Cu" signal "TOP")
		(4 "In1.Cu" signal "L2GND")
		(6 "In2.Cu" signal "L3")
		(8 "In3.Cu" signal "L4GND")
		(10 "In4.Cu" signal "L5")
		(12 "In5.Cu" signal "L6GND")
		(14 "In6.Cu" signal "L7VCC")
		(16 "In7.Cu" signal "L8VCC")
		(18 "In8.Cu" signal "L9GND")
		(20 "In9.Cu" signal "L10")
		(22 "In10.Cu" signal "L11GND")
		(24 "In11.Cu" signal "L12")
		(26 "In12.Cu" signal "L13GND")
		(2 "B.Cu" signal "BOTTOM")
		(9 "F.Adhes" user "F.Adhesive")
		(11 "B.Adhes" user "B.Adhesive")
		(13 "F.Paste" user "Package Geometry/Pastemask Top")
		(15 "B.Paste" user "Package Geometry/Pastemask Bottom")
		(5 "F.SilkS" user "Ref Des/Silkscreen Top")
		(7 "B.SilkS" user "Ref Des/Silkscreen Bottom")
		(1 "F.Mask" user "Board Geometry/Soldermask Top")
		(3 "B.Mask" user "Board Geometry/Soldermask Bottom")
		(17 "Dwgs.User" user "User.Drawings")
		(19 "Cmts.User" user "User.Comments")
		(21 "Eco1.User" user "User.Eco1")
		(23 "Eco2.User" user "User.Eco2")
		(25 "Edge.Cuts" user "Board Geometry/Outline")
		(27 "Margin" user)
		(31 "F.CrtYd" user "Package Geometry/Place Bound Top")
		(29 "B.CrtYd" user "Package Geometry/Place Bound Bottom")
		(35 "F.Fab" user "Ref Des/Assembly Top")
		(33 "B.Fab" user "Ref Des/Assembly Bottom")
	)
	(footprint ""
		(layer "F.Cu")
		(at 497.05006 -57.079896 90)
		(property "Reference" "J30W1"
			(at 0 0 90)
			(layer "F.SilkS")
			(hide yes)
			(effects
				(font
					(size 1.27 1.27)
				)
			)
		)
		(property "Value" "*"
			(at 6.604 -3.1623 90)
			(unlocked yes)
			(layer "F.Fab")
			(hide yes)
			(effects
				(font
					(size 1.27 1.016)
					(thickness 0.1524)
				)
			)
		)
		(property "Device Type" "SKT-USB32-8-GP_SOCKET-G4-SKT-UA"
			(at 6.604 -4.6863 90)
			(unlocked yes)
			(layer "F.Fab")
			(hide yes)
			(effects
				(font
					(size 1.27 1.016)
					(thickness 0.1524)
				)
			)
		)
		(duplicate_pad_numbers_are_jumpers no)
		(pad "PTH8" thru_hole oval
			(at 4.500118 3.50012 90)
			(size 1.2192 2.3876)
			(drill oval 0.508 1.524
				(offset 0 -0.199898)
			)
			(layers "*.Cu" "*.Mask")
			(remove_unused_layers no)
			(net "GND")
			(clearance 0.1524)
			(thermal_gap 0.1524)
		)
	)
)
